(kicad_pcb
	(version 20260206)
	(generator "pcbnew")
	(generator_version "10.0")
	(general
		(thickness 1.6)
		(legacy_teardrops no)
	)
	(paper "A4")
	(title_block
		(title "04192023_DAF0TMB3IC0_F0TG_MB_C_brd_V02_OCP.brd")
		(comment 1 "Grand Teton / footprints 7314-7320 of 8354")
	)
	(layers
		(0 "F.Cu" signal "TOP")
		(4 "In1.Cu" signal "GND")
		(6 "In2.Cu" signal "IN1")
		(8 "In3.Cu" signal "GND1")
		(10 "In4.Cu" signal "IN2")
		(12 "In5.Cu" signal "GND2")
		(14 "In6.Cu" signal "IN3")
		(16 "In7.Cu" signal "GND3")
		(18 "In8.Cu" signal "VCC")
		(20 "In9.Cu" signal "VCC1")
		(22 "In10.Cu" signal "GND4")
		(24 "In11.Cu" signal "IN4")
		(26 "In12.Cu" signal "GND5")
		(28 "In13.Cu" signal "IN5")
		(30 "In14.Cu" signal "GND6")
		(32 "In15.Cu" signal "IN6")
		(34 "In16.Cu" signal "GND7")
		(2 "B.Cu" signal "BOTTOM")
		(9 "F.Adhes" user "F.Adhesive")
		(11 "B.Adhes" user "B.Adhesive")
		(13 "F.Paste" user "Package Geometry/Pastemask Top")
		(15 "B.Paste" user "Package Geometry/Pastemask Bottom")
		(5 "F.SilkS" user "Ref Des/Silkscreen Top")
		(7 "B.SilkS" user "Ref Des/Silkscreen Bottom")
		(1 "F.Mask" user "Board Geometry/Soldermask Top")
		(3 "B.Mask" user "Board Geometry/Soldermask Bottom")
		(17 "Dwgs.User" user "User.Drawings")
		(19 "Cmts.User" user "User.Comments")
		(21 "Eco1.User" user "User.Eco1")
		(23 "Eco2.User" user "User.Eco2")
		(25 "Edge.Cuts" user "Board Geometry/Outline")
		(27 "Margin" user)
		(31 "F.CrtYd" user "Package Geometry/Place Bound Top")
		(29 "B.CrtYd" user "Package Geometry/Place Bound Bottom")
		(35 "F.Fab" user "Ref Des/Assembly Top")
		(33 "B.Fab" user "Ref Des/Assembly Bottom")
	)
	(footprint ""
		(layer "B.Cu")
		(at 171.2341 -113.589308)
		(property "Reference" "R58"
			(at 0 0 0)
			(layer "B.SilkS")
			(hide yes)
			(effects
				(font
					(size 1.27 1.27)
				)
				(justify mirror)
			)
		)
		(property "Value" ""
			(at 0 0 0)
			(layer "B.Fab")
			(effects
				(font
					(size 1.27 1.27)
				)
				(justify mirror)
			)
		)
		(duplicate_pad_numbers_are_jumpers no)
		(fp_line
			(start -0.7874 -0.4064)
			(end -0.7874 0.4064)
			(stroke
				(width 0.1524)
				(type default)
			)
			(layer "B.SilkS")
		)
		(fp_line
			(start -0.7874 0.4064)
			(end 0.7874 0.4064)
			(stroke
				(width 0.1524)
				(type default)
			)
			(layer "B.SilkS")
		)
		(fp_line
			(start 0.7874 -0.4064)
			(end -0.7874 -0.4064)
			(stroke
				(width 0.1524)
				(type default)
			)
			(layer "B.SilkS")
		)
		(fp_line
			(start 0.7874 0.4064)
			(end 0.7874 -0.4064)
			(stroke
				(width 0.1524)
				(type default)
			)
			(layer "B.SilkS")
		)
		(fp_line
			(start -0.67945 -0.3048)
			(end -0.67945 0.3048)
			(stroke
				(width 0.1)
				(type default)
			)
			(layer "B.Fab")
		)
		(fp_line
			(start -0.67945 0.3048)
			(end -0.120396 0.3048)
			(stroke
				(width 0.1)
				(type default)
			)
			(layer "B.Fab")
		)
		(fp_line
			(start -0.12065 -0.3048)
			(end -0.67945 -0.3048)
			(stroke
				(width 0.1)
				(type default)
			)
			(layer "B.Fab")
		)
		(fp_line
			(start -0.12065 -0.2794)
			(end -0.12065 -0.3048)
			(stroke
				(width 0.1)
				(type default)
			)
			(layer "B.Fab")
		)
		(fp_line
			(start -0.120396 0.2794)
			(end 0.12065 0.2794)
			(stroke
				(width 0.1)
				(type default)
			)
			(layer "B.Fab")
		)
		(fp_line
			(start -0.120396 0.3048)
			(end -0.120396 0.2794)
			(stroke
				(width 0.1)
				(type default)
			)
			(layer "B.Fab")
		)
		(fp_line
			(start 0.12065 -0.305054)
			(end 0.12065 -0.2794)
			(stroke
				(width 0.1)
				(type default)
			)
			(layer "B.Fab")
		)
		(fp_line
			(start 0.12065 -0.2794)
			(end -0.12065 -0.2794)
			(stroke
				(width 0.1)
				(type default)
			)
			(layer "B.Fab")
		)
		(fp_line
			(start 0.12065 0.2794)
			(end 0.12065 0.3048)
			(stroke
				(width 0.1)
				(type default)
			)
			(layer "B.Fab")
		)
		(fp_line
			(start 0.12065 0.3048)
			(end 0.67945 0.3048)
			(stroke
				(width 0.1)
				(type default)
			)
			(layer "B.Fab")
		)
		(fp_line
			(start 0.67945 -0.305054)
			(end 0.12065 -0.305054)
			(stroke
				(width 0.1)
				(type default)
			)
			(layer "B.Fab")
		)
		(fp_line
			(start 0.67945 0.3048)
			(end 0.67945 -0.305054)
			(stroke
				(width 0.1)
				(type default)
			)
			(layer "B.Fab")
		)
		(pad "1" smd circle
			(at 0.40005 0 180)
			(size 0 0)
			(layers "B.Cu" "B.Mask" "B.Paste")
			(net "SGPIO_SCM_INTR_R_N")
		)
		(pad "2" smd circle
			(at -0.40005 0 180)
			(size 0 0)
			(layers "B.Cu" "B.Mask" "B.Paste")
			(net "SGPIO_SCM_INTR_N")
		)
	)
	(footprint ""
		(layer "B.Cu")
		(at 401.554696 -341.172292 90)
		(property "Reference" "C218"
			(at 0 0 90)
			(layer "B.SilkS")
			(hide yes)
			(effects
				(font
					(size 1.27 1.27)
				)
				(justify mirror)
			)
		)
		(property "Value" ""
			(at 0 0 90)
			(layer "B.Fab")
			(effects
				(font
					(size 1.27 1.27)
				)
				(justify mirror)
			)
		)
		(duplicate_pad_numbers_are_jumpers no)
		(fp_line
			(start 0.7874 -0.4064)
			(end -0.7874 -0.4064)
			(stroke
				(width 0.1524)
				(type default)
			)
			(layer "B.SilkS")
		)
		(fp_line
			(start -0.7874 -0.4064)
			(end -0.7874 0.4064)
			(stroke
				(width 0.1524)
				(type default)
			)
			(layer "B.SilkS")
		)
		(fp_line
			(start 0.7874 0.4064)
			(end 0.7874 -0.4064)
			(stroke
				(width 0.1524)
				(type default)
			)
			(layer "B.SilkS")
		)
		(fp_line
			(start -0.7874 0.4064)
			(end 0.7874 0.4064)
			(stroke
				(width 0.1524)
				(type default)
			)
			(layer "B.SilkS")
		)
		(fp_line
			(start 0.67945 -0.305054)
			(end 0.12065 -0.305054)
			(stroke
				(width 0.1)
				(type default)
			)
			(layer "B.Fab")
		)
		(fp_line
			(start 0.12065 -0.305054)
			(end 0.12065 -0.2794)
			(stroke
				(width 0.1)
				(type default)
			)
			(layer "B.Fab")
		)
		(fp_line
			(start -0.12065 -0.3048)
			(end -0.67945 -0.3048)
			(stroke
				(width 0.1)
				(type default)
			)
			(layer "B.Fab")
		)
		(fp_line
			(start -0.67945 -0.3048)
			(end -0.67945 0.3048)
			(stroke
				(width 0.1)
				(type default)
			)
			(layer "B.Fab")
		)
		(fp_line
			(start 0.12065 -0.2794)
			(end -0.12065 -0.2794)
			(stroke
				(width 0.1)
				(type default)
			)
			(layer "B.Fab")
		)
		(fp_line
			(start -0.12065 -0.2794)
			(end -0.12065 -0.3048)
			(stroke
				(width 0.1)
				(type default)
			)
			(layer "B.Fab")
		)
		(fp_line
			(start 0.12065 0.2794)
			(end 0.12065 0.3048)
			(stroke
				(width 0.1)
				(type default)
			)
			(layer "B.Fab")
		)
		(fp_line
			(start -0.120396 0.2794)
			(end 0.12065 0.2794)
			(stroke
				(width 0.1)
				(type default)
			)
			(layer "B.Fab")
		)
		(fp_line
			(start 0.67945 0.3048)
			(end 0.67945 -0.305054)
			(stroke
				(width 0.1)
				(type default)
			)
			(layer "B.Fab")
		)
		(fp_line
			(start 0.12065 0.3048)
			(end 0.67945 0.3048)
			(stroke
				(width 0.1)
				(type default)
			)
			(layer "B.Fab")
		)
		(fp_line
			(start -0.120396 0.3048)
			(end -0.120396 0.2794)
			(stroke
				(width 0.1)
				(type default)
			)
			(layer "B.Fab")
		)
		(fp_line
			(start -0.67945 0.3048)
			(end -0.120396 0.3048)
			(stroke
				(width 0.1)
				(type default)
			)
			(layer "B.Fab")
		)
		(pad "1" smd circle
			(at 0.40005 0 270)
			(size 0 0)
			(layers "B.Cu" "B.Mask" "B.Paste")
			(net "P1V8_AUX")
		)
		(pad "2" smd circle
			(at -0.40005 0 270)
			(size 0 0)
			(layers "B.Cu" "B.Mask" "B.Paste")
			(net "GND")
		)
	)
	(footprint ""
		(layer "B.Cu")
		(at 527.561048 -24.162512)
		(property "Reference" "DB16"
			(at 2.586228 -5.512308 270)
			(unlocked yes)
			(layer "B.SilkS")
			(effects
				(font
					(size 0.7874 0.5842)
					(thickness 0.1524)
				)
				(justify left mirror)
			)
		)
		(property "Value" ""
			(at 0 0 0)
			(layer "B.Fab")
			(effects
				(font
					(size 1.27 1.27)
				)
				(justify mirror)
			)
		)
		(duplicate_pad_numbers_are_jumpers no)
		(fp_line
			(start -3.330702 -4.771136)
			(end 0 4.011168)
			(stroke
				(width 0.1524)
				(type default)
			)
			(layer "B.SilkS")
		)
		(fp_line
			(start 0 4.011168)
			(end 3.330702 -4.771136)
			(stroke
				(width 0.1524)
				(type default)
			)
			(layer "B.SilkS")
		)
		(fp_line
			(start 3.330702 -4.771136)
			(end -3.330702 -4.771136)
			(stroke
				(width 0.1524)
				(type default)
			)
			(layer "B.SilkS")
		)
		(fp_line
			(start -3.330702 -4.771136)
			(end 0 4.011168)
			(stroke
				(width 0.1)
				(type default)
			)
			(layer "B.Fab")
		)
		(fp_line
			(start 0 4.011168)
			(end 3.330702 -4.771136)
			(stroke
				(width 0.1)
				(type default)
			)
			(layer "B.Fab")
		)
		(fp_line
			(start 3.330702 -4.771136)
			(end -3.330702 -4.771136)
			(stroke
				(width 0.1)
				(type default)
			)
			(layer "B.Fab")
		)
		(pad "1" thru_hole circle
			(at 0 0 180)
			(size 2.159 2.159)
			(drill 1.7018)
			(layers "*.Cu" "*.Mask")
			(remove_unused_layers no)
			(net "T1_GND")
			(clearance 0.0254)
			(thermal_gap 0.0254)
		)
		(pad "2" thru_hole circle
			(at 1.27 -3.348736 180)
			(size 2.159 2.159)
			(drill 1.7018)
			(layers "*.Cu" "*.Mask")
			(remove_unused_layers no)
			(net "TDR_SE_50_OHM_IN6")
			(clearance 0.0254)
			(thermal_gap 0.0254)
		)
		(pad "3" thru_hole circle
			(at -1.27 -3.348736 180)
			(size 2.159 2.159)
			(drill 1.7018)
			(layers "*.Cu" "*.Mask")
			(remove_unused_layers no)
			(net "TDR_SE_50_OHM_IN6")
			(clearance 0.0254)
			(thermal_gap 0.0254)
		)
	)
	(footprint ""
		(layer "B.Cu")
		(at 400.13509 -176.111916 90)
		(property "Reference" "PR356"
			(at 0 0 90)
			(layer "B.SilkS")
			(hide yes)
			(effects
				(font
					(size 1.27 1.27)
				)
				(justify mirror)
			)
		)
		(property "Value" ""
			(at 0 0 90)
			(layer "B.Fab")
			(effects
				(font
					(size 1.27 1.27)
				)
				(justify mirror)
			)
		)
		(duplicate_pad_numbers_are_jumpers no)
		(fp_line
			(start 0.7874 -0.4064)
			(end -0.7874 -0.4064)
			(stroke
				(width 0.1524)
				(type default)
			)
			(layer "B.SilkS")
		)
		(fp_line
			(start -0.7874 -0.4064)
			(end -0.7874 0.4064)
			(stroke
				(width 0.1524)
				(type default)
			)
			(layer "B.SilkS")
		)
		(fp_line
			(start 0.7874 0.4064)
			(end 0.7874 -0.4064)
			(stroke
				(width 0.1524)
				(type default)
			)
			(layer "B.SilkS")
		)
		(fp_line
			(start -0.7874 0.4064)
			(end 0.7874 0.4064)
			(stroke
				(width 0.1524)
				(type default)
			)
			(layer "B.SilkS")
		)
		(fp_line
			(start 0.67945 -0.305054)
			(end 0.12065 -0.305054)
			(stroke
				(width 0.1)
				(type default)
			)
			(layer "B.Fab")
		)
		(fp_line
			(start 0.12065 -0.305054)
			(end 0.12065 -0.2794)
			(stroke
				(width 0.1)
				(type default)
			)
			(layer "B.Fab")
		)
		(fp_line
			(start -0.12065 -0.3048)
			(end -0.67945 -0.3048)
			(stroke
				(width 0.1)
				(type default)
			)
			(layer "B.Fab")
		)
		(fp_line
			(start -0.67945 -0.3048)
			(end -0.67945 0.3048)
			(stroke
				(width 0.1)
				(type default)
			)
			(layer "B.Fab")
		)
		(fp_line
			(start 0.12065 -0.2794)
			(end -0.12065 -0.2794)
			(stroke
				(width 0.1)
				(type default)
			)
			(layer "B.Fab")
		)
		(fp_line
			(start -0.12065 -0.2794)
			(end -0.12065 -0.3048)
			(stroke
				(width 0.1)
				(type default)
			)
			(layer "B.Fab")
		)
		(fp_line
			(start 0.12065 0.2794)
			(end 0.12065 0.3048)
			(stroke
				(width 0.1)
				(type default)
			)
			(layer "B.Fab")
		)
		(fp_line
			(start -0.120396 0.2794)
			(end 0.12065 0.2794)
			(stroke
				(width 0.1)
				(type default)
			)
			(layer "B.Fab")
		)
		(fp_line
			(start 0.67945 0.3048)
			(end 0.67945 -0.305054)
			(stroke
				(width 0.1)
				(type default)
			)
			(layer "B.Fab")
		)
		(fp_line
			(start 0.12065 0.3048)
			(end 0.67945 0.3048)
			(stroke
				(width 0.1)
				(type default)
			)
			(layer "B.Fab")
		)
		(fp_line
			(start -0.120396 0.3048)
			(end -0.120396 0.2794)
			(stroke
				(width 0.1)
				(type default)
			)
			(layer "B.Fab")
		)
		(fp_line
			(start -0.67945 0.3048)
			(end -0.120396 0.3048)
			(stroke
				(width 0.1)
				(type default)
			)
			(layer "B.Fab")
		)
		(pad "1" smd circle
			(at 0.40005 0 270)
			(size 0 0)
			(layers "B.Cu" "B.Mask" "B.Paste")
			(net "PVDDCR_CPU0_P0_PVCC")
		)
		(pad "2" smd circle
			(at -0.40005 0 270)
			(size 0 0)
			(layers "B.Cu" "B.Mask" "B.Paste")
			(net "PVDDCR_SOC_P0_VCC1")
		)
	)
	(footprint ""
		(layer "B.Cu")
		(at 428.98695 -33.467548 180)
		(property "Reference" "R1357"
			(at 0 0 0)
			(layer "B.SilkS")
			(hide yes)
			(effects
				(font
					(size 1.27 1.27)
				)
				(justify mirror)
			)
		)
		(property "Value" ""
			(at 0 0 0)
			(layer "B.Fab")
			(effects
				(font
					(size 1.27 1.27)
				)
				(justify mirror)
			)
		)
		(duplicate_pad_numbers_are_jumpers no)
		(fp_line
			(start 0.7874 0.4064)
			(end 0.7874 -0.4064)
			(stroke
				(width 0.1524)
				(type default)
			)
			(layer "B.SilkS")
		)
		(fp_line
			(start 0.7874 -0.4064)
			(end -0.7874 -0.4064)
			(stroke
				(width 0.1524)
				(type default)
			)
			(layer "B.SilkS")
		)
		(fp_line
			(start -0.7874 0.4064)
			(end 0.7874 0.4064)
			(stroke
				(width 0.1524)
				(type default)
			)
			(layer "B.SilkS")
		)
		(fp_line
			(start -0.7874 -0.4064)
			(end -0.7874 0.4064)
			(stroke
				(width 0.1524)
				(type default)
			)
			(layer "B.SilkS")
		)
		(fp_line
			(start 0.67945 0.3048)
			(end 0.67945 -0.305054)
			(stroke
				(width 0.1)
				(type default)
			)
			(layer "B.Fab")
		)
		(fp_line
			(start 0.67945 -0.305054)
			(end 0.12065 -0.305054)
			(stroke
				(width 0.1)
				(type default)
			)
			(layer "B.Fab")
		)
		(fp_line
			(start 0.12065 0.3048)
			(end 0.67945 0.3048)
			(stroke
				(width 0.1)
				(type default)
			)
			(layer "B.Fab")
		)
		(fp_line
			(start 0.12065 0.2794)
			(end 0.12065 0.3048)
			(stroke
				(width 0.1)
				(type default)
			)
			(layer "B.Fab")
		)
		(fp_line
			(start 0.12065 -0.2794)
			(end -0.12065 -0.2794)
			(stroke
				(width 0.1)
				(type default)
			)
			(layer "B.Fab")
		)
		(fp_line
			(start 0.12065 -0.305054)
			(end 0.12065 -0.2794)
			(stroke
				(width 0.1)
				(type default)
			)
			(layer "B.Fab")
		)
		(fp_line
			(start -0.120396 0.3048)
			(end -0.120396 0.2794)
			(stroke
				(width 0.1)
				(type default)
			)
			(layer "B.Fab")
		)
		(fp_line
			(start -0.120396 0.2794)
			(end 0.12065 0.2794)
			(stroke
				(width 0.1)
				(type default)
			)
			(layer "B.Fab")
		)
		(fp_line
			(start -0.12065 -0.2794)
			(end -0.12065 -0.3048)
			(stroke
				(width 0.1)
				(type default)
			)
			(layer "B.Fab")
		)
		(fp_line
			(start -0.12065 -0.3048)
			(end -0.67945 -0.3048)
			(stroke
				(width 0.1)
				(type default)
			)
			(layer "B.Fab")
		)
		(fp_line
			(start -0.67945 0.3048)
			(end -0.120396 0.3048)
			(stroke
				(width 0.1)
				(type default)
			)
			(layer "B.Fab")
		)
		(fp_line
			(start -0.67945 -0.3048)
			(end -0.67945 0.3048)
			(stroke
				(width 0.1)
				(type default)
			)
			(layer "B.Fab")
		)
		(pad "1" smd circle
			(at 0.40005 0)
			(size 0 0)
			(layers "B.Cu" "B.Mask" "B.Paste")
			(net "P3V3_AUX")
		)
		(pad "2" smd circle
			(at -0.40005 0)
			(size 0 0)
			(layers "B.Cu" "B.Mask" "B.Paste")
			(net "FM_PRSNT_CPU1_N")
		)
	)
	(footprint ""
		(layer "B.Cu")
		(at 308.080664 -73.534778)
		(property "Reference" "Q6000"
			(at 1.4224 -1.768348 0)
			(unlocked yes)
			(layer "B.SilkS")
			(effects
				(font
					(size 0.7874 0.5842)
					(thickness 0.1524)
				)
				(justify left mirror)
			)
		)
		(property "Value" ""
			(at 0 0 0)
			(layer "B.Fab")
			(effects
				(font
					(size 1.27 1.27)
				)
				(justify mirror)
			)
		)
		(duplicate_pad_numbers_are_jumpers no)
		(fp_line
			(start -1.332738 -1.100074)
			(end -1.332738 1.100074)
			(stroke
				(width 0.1524)
				(type default)
			)
			(layer "B.SilkS")
		)
		(fp_line
			(start -1.332738 1.100074)
			(end 1.332738 1.100074)
			(stroke
				(width 0.1524)
				(type default)
			)
			(layer "B.SilkS")
		)
		(fp_line
			(start -0.4826 -1.100074)
			(end -1.332738 -1.100074)
			(stroke
				(width 0.1524)
				(type default)
			)
			(layer "B.SilkS")
		)
		(fp_line
			(start 0 -0.541274)
			(end -0.4826 -1.100074)
			(stroke
				(width 0.1524)
				(type default)
			)
			(layer "B.SilkS")
		)
		(fp_line
			(start 0.4826 -1.100074)
			(end 0 -0.541274)
			(stroke
				(width 0.1524)
				(type default)
			)
			(layer "B.SilkS")
		)
		(fp_line
			(start 1.332738 -1.100074)
			(end 0.4826 -1.100074)
			(stroke
				(width 0.1524)
				(type default)
			)
			(layer "B.SilkS")
		)
		(fp_line
			(start 1.332738 1.100074)
			(end 1.332738 -1.100074)
			(stroke
				(width 0.1524)
				(type default)
			)
			(layer "B.SilkS")
		)
		(fp_poly
			(pts
				(xy 1.334516 -0.672084) (xy 2.036572 -1.023112) (xy 2.036572 -0.321056)
			)
			(stroke
				(width 0)
				(type default)
			)
			(fill yes)
			(layer "B.SilkS")
		)
		(fp_line
			(start -0.674878 -1.100074)
			(end -0.674878 1.100074)
			(stroke
				(width 0.1)
				(type default)
			)
			(layer "B.Fab")
		)
		(fp_line
			(start -0.674878 1.100074)
			(end 0.674878 1.100074)
			(stroke
				(width 0.1)
				(type default)
			)
			(layer "B.Fab")
		)
		(fp_line
			(start 0.674878 -1.100074)
			(end -0.674878 -1.100074)
			(stroke
				(width 0.1)
				(type default)
			)
			(layer "B.Fab")
		)
		(fp_line
			(start 0.674878 1.100074)
			(end 0.674878 -1.100074)
			(stroke
				(width 0.1)
				(type default)
			)
			(layer "B.Fab")
		)
		(fp_poly
			(pts
				(xy 2.2352 -0.298958) (xy 2.2352 -1.001014) (xy 1.533144 -0.649986)
			)
			(stroke
				(width 0)
				(type default)
			)
			(fill yes)
			(layer "B.Fab")
		)
		(pad "1" smd rect
			(at 0.94996 -0.649986 90)
			(size 0.4318 0.508)
			(layers "B.Cu" "B.Mask" "B.Paste")
			(net "GND")
		)
		(pad "2" smd rect
			(at 0.94996 0 90)
			(size 0.4318 0.508)
			(layers "B.Cu" "B.Mask" "B.Paste")
			(net "PWRGD_P1V2_AUX_R")
		)
		(pad "3" smd rect
			(at 0.94996 0.649986 90)
			(size 0.4318 0.508)
			(layers "B.Cu" "B.Mask" "B.Paste")
			(net "Net_10797")
		)
		(pad "4" smd rect
			(at -0.94996 0.649986 90)
			(size 0.4318 0.508)
			(layers "B.Cu" "B.Mask" "B.Paste")
			(net "Net_10795")
		)
		(pad "5" smd rect
			(at -0.94996 0 90)
			(size 0.4318 0.508)
			(layers "B.Cu" "B.Mask" "B.Paste")
			(net "Net_10796")
		)
		(pad "6" smd rect
			(at -0.94996 -0.649986 90)
			(size 0.4318 0.508)
			(layers "B.Cu" "B.Mask" "B.Paste")
			(net "LED_PWRGD_P1V2_AUX_D")
		)
	)
	(footprint ""
		(layer "B.Cu")
		(at 21.70811 -192.66027)
		(property "Reference" "C527"
			(at 0 0 0)
			(layer "B.SilkS")
			(hide yes)
			(effects
				(font
					(size 1.27 1.27)
				)
				(justify mirror)
			)
		)
		(property "Value" ""
			(at 0 0 0)
			(layer "B.Fab")
			(effects
				(font
					(size 1.27 1.27)
				)
				(justify mirror)
			)
		)
		(duplicate_pad_numbers_are_jumpers no)
		(fp_line
			(start -1.524 -0.762)
			(end -1.524 0.762)
			(stroke
				(width 0.1524)
				(type default)
			)
			(layer "B.SilkS")
		)
		(fp_line
			(start -1.524 0.762)
			(end 1.524 0.762)
			(stroke
				(width 0.1524)
				(type default)
			)
			(layer "B.SilkS")
		)
		(fp_line
			(start 1.524 -0.762)
			(end -1.524 -0.762)
			(stroke
				(width 0.1524)
				(type default)
			)
			(layer "B.SilkS")
		)
		(fp_line
			(start 1.524 0.762)
			(end 1.524 -0.762)
			(stroke
				(width 0.1524)
				(type default)
			)
			(layer "B.SilkS")
		)
		(fp_line
			(start -1.1049 -0.724916)
			(end 1.1049 -0.724916)
			(stroke
				(width 0.1)
				(type default)
			)
			(layer "B.Fab")
		)
		(fp_line
			(start -1.1049 0.724916)
			(end -1.1049 -0.724916)
			(stroke
				(width 0.1)
				(type default)
			)
			(layer "B.Fab")
		)
		(fp_line
			(start 1.1049 -0.724916)
			(end 1.1049 0.724916)
			(stroke
				(width 0.1)
				(type default)
			)
			(layer "B.Fab")
		)
		(fp_line
			(start 1.1049 0.724916)
			(end -1.1049 0.724916)
			(stroke
				(width 0.1)
				(type default)
			)
			(layer "B.Fab")
		)
		(pad "1" smd rect
			(at 0.889 0)
			(size 1.016 1.27)
			(layers "B.Cu" "B.Mask" "B.Paste")
			(net "P12V_MEM_CPU1")
		)
		(pad "2" smd rect
			(at -0.889 0)
			(size 1.016 1.27)
			(layers "B.Cu" "B.Mask" "B.Paste")
			(net "GND")
		)
	)
)
